# SCM (Grand Teton) — schematic netlist excerpt (pin names and nets, part order shuffled) for the footprints in the layout excerpt that follows; sources: Cadence DE-HDL packaged netlist, KiCad conversion of 12092022_DA0F0TMDCD0_F0T_Management_Board_D_brd_V3_OCP.brd

C170  Q_CAP  0.01UF 50V 10% X7R  pkg C0402  page 20 : A = P0V6_DDR_VREF_AUX ; B = GND
C237  Q_CAP  0.1UF 25V 10% X7R  pkg 0402  page 29 : A = P3V3_AUX ; B = GND

(kicad_pcb
	(version 20260206)
	(generator "pcbnew")
	(generator_version "10.0")
	(general
		(thickness 1.6)
		(legacy_teardrops no)
	)
	(paper "A4")
	(title_block
		(title "12092022_DA0F0TMDCD0_F0T_Management_Board_D_brd_V3_OCP.brd")
		(comment 1 "Grand Teton / footprints 1066-1067 of 1440")
	)
	(layers
		(0 "F.Cu" signal "TOP")
		(4 "In1.Cu" signal "GND")
		(6 "In2.Cu" signal "IN1")
		(8 "In3.Cu" signal "GND1")
		(10 "In4.Cu" signal "IN2")
		(12 "In5.Cu" signal "VCC")
		(14 "In6.Cu" signal "VCC1")
		(16 "In7.Cu" signal "IN3")
		(18 "In8.Cu" signal "GND2")
		(20 "In9.Cu" signal "IN4")
		(22 "In10.Cu" signal "GND3")
		(2 "B.Cu" signal "BOTTOM")
		(9 "F.Adhes" user "F.Adhesive")
		(11 "B.Adhes" user "B.Adhesive")
		(13 "F.Paste" user "Package Geometry/Pastemask Top")
		(15 "B.Paste" user "Package Geometry/Pastemask Bottom")
		(5 "F.SilkS" user "Ref Des/Silkscreen Top")
		(7 "B.SilkS" user "Ref Des/Silkscreen Bottom")
		(1 "F.Mask" user "Board Geometry/Soldermask Top")
		(3 "B.Mask" user "Board Geometry/Soldermask Bottom")
		(17 "Dwgs.User" user "User.Drawings")
		(19 "Cmts.User" user "User.Comments")
		(21 "Eco1.User" user "User.Eco1")
		(23 "Eco2.User" user "User.Eco2")
		(25 "Edge.Cuts" user "Board Geometry/Outline")
		(27 "Margin" user)
		(31 "F.CrtYd" user "Package Geometry/Place Bound Top")
		(29 "B.CrtYd" user "Package Geometry/Place Bound Bottom")
		(35 "F.Fab" user "Ref Des/Assembly Top")
		(33 "B.Fab" user "Ref Des/Assembly Bottom")
	)
	(footprint ""
		(layer "B.Cu")
		(at 46.0756 -92.5322 -90)
		(property "Reference" "C237"
			(at 0 0 90)
			(layer "B.SilkS")
			(hide yes)
			(effects
				(font
					(size 1.27 1.27)
				)
				(justify mirror)
			)
		)
		(property "Value" ""
			(at 0 0 90)
			(layer "B.Fab")
			(effects
				(font
					(size 1.27 1.27)
				)
				(justify mirror)
			)
		)
		(duplicate_pad_numbers_are_jumpers no)
		(fp_line
			(start -0.7874 0.4064)
			(end 0.7874 0.4064)
			(stroke
				(width 0.1524)
				(type default)
			)
			(layer "B.SilkS")
		)
		(fp_line
			(start 0.7874 0.4064)
			(end 0.7874 -0.4064)
			(stroke
				(width 0.1524)
				(type default)
			)
			(layer "B.SilkS")
		)
		(fp_line
			(start -0.7874 -0.4064)
			(end -0.7874 0.4064)
			(stroke
				(width 0.1524)
				(type default)
			)
			(layer "B.SilkS")
		)
		(fp_line
			(start 0.7874 -0.4064)
			(end -0.7874 -0.4064)
			(stroke
				(width 0.1524)
				(type default)
			)
			(layer "B.SilkS")
		)
		(fp_line
			(start -0.67945 0.3048)
			(end -0.120396 0.3048)
			(stroke
				(width 0.1)
				(type default)
			)
			(layer "B.Fab")
		)
		(fp_line
			(start -0.120396 0.3048)
			(end -0.120396 0.2794)
			(stroke
				(width 0.1)
				(type default)
			)
			(layer "B.Fab")
		)
		(fp_line
			(start 0.12065 0.3048)
			(end 0.67945 0.3048)
			(stroke
				(width 0.1)
				(type default)
			)
			(layer "B.Fab")
		)
		(fp_line
			(start 0.67945 0.3048)
			(end 0.67945 -0.305054)
			(stroke
				(width 0.1)
				(type default)
			)
			(layer "B.Fab")
		)
		(fp_line
			(start -0.120396 0.2794)
			(end 0.12065 0.2794)
			(stroke
				(width 0.1)
				(type default)
			)
			(layer "B.Fab")
		)
		(fp_line
			(start 0.12065 0.2794)
			(end 0.12065 0.3048)
			(stroke
				(width 0.1)
				(type default)
			)
			(layer "B.Fab")
		)
		(fp_line
			(start -0.12065 -0.2794)
			(end -0.12065 -0.3048)
			(stroke
				(width 0.1)
				(type default)
			)
			(layer "B.Fab")
		)
		(fp_line
			(start 0.12065 -0.2794)
			(end -0.12065 -0.2794)
			(stroke
				(width 0.1)
				(type default)
			)
			(layer "B.Fab")
		)
		(fp_line
			(start -0.67945 -0.3048)
			(end -0.67945 0.3048)
			(stroke
				(width 0.1)
				(type default)
			)
			(layer "B.Fab")
		)
		(fp_line
			(start -0.12065 -0.3048)
			(end -0.67945 -0.3048)
			(stroke
				(width 0.1)
				(type default)
			)
			(layer "B.Fab")
		)
		(fp_line
			(start 0.12065 -0.305054)
			(end 0.12065 -0.2794)
			(stroke
				(width 0.1)
				(type default)
			)
			(layer "B.Fab")
		)
		(fp_line
			(start 0.67945 -0.305054)
			(end 0.12065 -0.305054)
			(stroke
				(width 0.1)
				(type default)
			)
			(layer "B.Fab")
		)
		(pad "1" smd circle
			(at 0.40005 0 90)
			(size 0 0)
			(layers "B.Cu" "B.Mask" "B.Paste")
			(net "P3V3_AUX")
		)
		(pad "2" smd circle
			(at -0.40005 0 90)
			(size 0 0)
			(layers "B.Cu" "B.Mask" "B.Paste")
			(net "GND")
		)
	)
	(footprint ""
		(layer "B.Cu")
		(at 84.08924 -51.381152 180)
		(property "Reference" "C170"
			(at 0 0 0)
			(layer "B.SilkS")
			(hide yes)
			(effects
				(font
					(size 1.27 1.27)
				)
				(justify mirror)
			)
		)
		(property "Value" ""
			(at 0 0 0)
			(layer "B.Fab")
			(effects
				(font
					(size 1.27 1.27)
				)
				(justify mirror)
			)
		)
		(duplicate_pad_numbers_are_jumpers no)
		(fp_line
			(start 0.7874 0.4064)
			(end 0.7874 -0.4064)
			(stroke
				(width 0.1524)
				(type default)
			)
			(layer "B.SilkS")
		)
		(fp_line
			(start 0.7874 -0.4064)
			(end -0.7874 -0.4064)
			(stroke
				(width 0.1524)
				(type default)
			)
			(layer "B.SilkS")
		)
		(fp_line
			(start -0.7874 0.4064)
			(end 0.7874 0.4064)
			(stroke
				(width 0.1524)
				(type default)
			)
			(layer "B.SilkS")
		)
		(fp_line
			(start -0.7874 -0.4064)
			(end -0.7874 0.4064)
			(stroke
				(width 0.1524)
				(type default)
			)
			(layer "B.SilkS")
		)
		(fp_line
			(start 0.67945 0.3048)
			(end 0.67945 -0.305054)
			(stroke
				(width 0.1)
				(type default)
			)
			(layer "B.Fab")
		)
		(fp_line
			(start 0.67945 -0.305054)
			(end 0.12065 -0.305054)
			(stroke
				(width 0.1)
				(type default)
			)
			(layer "B.Fab")
		)
		(fp_line
			(start 0.12065 0.3048)
			(end 0.67945 0.3048)
			(stroke
				(width 0.1)
				(type default)
			)
			(layer "B.Fab")
		)
		(fp_line
			(start 0.12065 0.2794)
			(end 0.12065 0.3048)
			(stroke
				(width 0.1)
				(type default)
			)
			(layer "B.Fab")
		)
		(fp_line
			(start 0.12065 -0.2794)
			(end -0.12065 -0.2794)
			(stroke
				(width 0.1)
				(type default)
			)
			(layer "B.Fab")
		)
		(fp_line
			(start 0.12065 -0.305054)
			(end 0.12065 -0.2794)
			(stroke
				(width 0.1)
				(type default)
			)
			(layer "B.Fab")
		)
		(fp_line
			(start -0.120396 0.3048)
			(end -0.120396 0.2794)
			(stroke
				(width 0.1)
				(type default)
			)
			(layer "B.Fab")
		)
		(fp_line
			(start -0.120396 0.2794)
			(end 0.12065 0.2794)
			(stroke
				(width 0.1)
				(type default)
			)
			(layer "B.Fab")
		)
		(fp_line
			(start -0.12065 -0.2794)
			(end -0.12065 -0.3048)
			(stroke
				(width 0.1)
				(type default)
			)
			(layer "B.Fab")
		)
		(fp_line
			(start -0.12065 -0.3048)
			(end -0.67945 -0.3048)
			(stroke
				(width 0.1)
				(type default)
			)
			(layer "B.Fab")
		)
		(fp_line
			(start -0.67945 0.3048)
			(end -0.120396 0.3048)
			(stroke
				(width 0.1)
				(type default)
			)
			(layer "B.Fab")
		)
		(fp_line
			(start -0.67945 -0.3048)
			(end -0.67945 0.3048)
			(stroke
				(width 0.1)
				(type default)
			)
			(layer "B.Fab")
		)
		(pad "1" smd circle
			(at 0.40005 0)
			(size 0 0)
			(layers "B.Cu" "B.Mask" "B.Paste")
			(net "P0V6_DDR_VREF_AUX")
		)
		(pad "2" smd circle
			(at -0.40005 0)
			(size 0 0)
			(layers "B.Cu" "B.Mask" "B.Paste")
			(net "GND")
		)
	)
)
